# T6G (Grand Teton) — schematic netlist excerpt (pin names and nets, part order shuffled) for the footprints in the layout excerpt that follows; sources: Cadence DE-HDL packaged netlist, KiCad conversion of 04192023_DAF0TMB3IC0_F0TG_MB_C_brd_V02_OCP.brd

J100  SCONN288_DDR506112002KQ  IO  pkg DDR288S_1-1VXC  page 106
  VIN_BULK0  = P12V_MEM_CPU1
  RFU0  = NC
  VIN_MGMT  = P3V3_AUX
  HSCL  = I3C_SPD_DDRI_CPU1_SCL
  HSDA  = I3C_SPD_DDRI_CPU1_SDA
  VSS0  = GND
  DQ0_A  = M_I_CPU1_SA_DQ<0>
  VSS1  = GND
  DQ1_A  = M_I_CPU1_SA_DQ<1>
  VSS2  = GND
  DQS0_A_T  = M_I_CPU1_SA_DQS_DP<0>
  DQS0_A_C  = M_I_CPU1_SA_DQS_DN<0>
  VSS3  = GND
  DQ4_A  = M_I_CPU1_SA_DQ<4>
  VSS4  = GND
  DQ5_A  = M_I_CPU1_SA_DQ<5>
  VSS5  = GND
  DQ8_A  = M_I_CPU1_SA_DQ<8>
  VSS6  = GND
  DQ9_A  = M_I_CPU1_SA_DQ<9>
  VSS7  = GND
  DQS1_A_T  = M_I_CPU1_SA_DQS_DP<1>
  DQS1_A_C  = M_I_CPU1_SA_DQS_DN<1>
  VSS8  = GND
  DQ12_A  = M_I_CPU1_SA_DQ<12>
  VSS9  = GND
  DQ13_A  = M_I_CPU1_SA_DQ<13>
  VSS10  = GND
  DQ16_A  = M_I_CPU1_SA_DQ<16>
  VSS11  = GND
  DQ17_A  = M_I_CPU1_SA_DQ<17>
  VSS12  = GND
  DQS2_A_T  = M_I_CPU1_SA_DQS_DP<2>
  DQS2_A_C  = M_I_CPU1_SA_DQS_DN<2>
  VSS13  = GND
  DQ20_A  = M_I_CPU1_SA_DQ<20>
  VSS14  = GND
  DQ21_A  = M_I_CPU1_SA_DQ<21>
  VSS15  = GND
  DQ24_A  = M_I_CPU1_SA_DQ<24>
  VSS16  = GND
  DQ25_A  = M_I_CPU1_SA_DQ<25>
  VSS17  = GND
  DQS3_A_T  = M_I_CPU1_SA_DQS_DP<3>
  DQS3_A_C  = M_I_CPU1_SA_DQS_DN<3>
  VSS18  = GND
  DQ28_A  = M_I_CPU1_SA_DQ<28>
  VSS19  = GND
  DQ29_A  = M_I_CPU1_SA_DQ<29>
  VSS20  = GND
  CB0_A  = M_I_CPU1_SA_CB<0>
  VSS21  = GND
  CB1_A  = M_I_CPU1_SA_CB<1>
  VSS22  = GND
  DQS4_A_T  = M_I_CPU1_SA_DQS_DP<4>
  DQS4_A_C  = M_I_CPU1_SA_DQS_DN<4>
  VSS23  = GND
  CB4_A  = M_I_CPU1_SA_CB<4>
  VSS24  = GND
  CB5_A  = M_I_CPU1_SA_CB<5>
  VSS25  = GND
  ALERT_N  = M_I_CPU1_ALERT_N
  VSS26  = GND
  CS0_A_N  = M_I_CPU1_SA_CS_N<0>
  VSS27  = GND
  CA0_A  = M_I_CPU1_SA_CA<0>
  VSS28  = GND
  CA2_A  = M_I_CPU1_SA_CA<2>
  VSS29  = GND
  CA4_A  = M_I_CPU1_SA_CA<4>
  VSS30  = GND
  CA6_A  = M_I_CPU1_SA_CA<6>
  VSS31  = GND
  PAR_A  = M_I_CPU1_SA_PAR
  VSS32  = GND
  CA0_B  = M_I_CPU1_SB_CA<0>
  VSS33  = GND
  CA2_B  = M_I_CPU1_SB_CA<2>
  VSS34  = GND
  CA4_B  = M_I_CPU1_SB_CA<4>
  VSS35  = GND
  CA6_B  = M_I_CPU1_SB_CA<6>
  VSS36  = GND
  CS0_B_N  = M_I_CPU1_SB_CS_N<0>
  VSS37  = GND
  \lbd||rsp_a_n\  = M_I_CPU1_SA_RSP<0>
  \lbs||rsp_b_n\  = M_I_CPU1_SB_RSP<0>
  VSS38  = GND
  CB4_B  = M_I_CPU1_SB_CB<4>
  VSS39  = GND
  CB5_B  = M_I_CPU1_SB_CB<5>
  VSS40  = GND
  \dqs9_b_t||tdqs9_b_t||dbi4_b_n\  = M_I_CPU1_SB_DQS_DP<9>
  \dqs9_b_c||tdqs9_b_c\  = M_I_CPU1_SB_DQS_DN<9>
  VSS41  = GND
  CB0_B  = M_I_CPU1_SB_CB<0>
  VSS42  = GND
  CB1_B  = M_I_CPU1_SB_CB<1>
  VSS43  = GND
  DQ0_B  = M_I_CPU1_SB_DQ<0>
  VSS44  = GND
  DQ1_B  = M_I_CPU1_SB_DQ<1>
  VSS45  = GND
  DQS0_B_T  = M_I_CPU1_SB_DQS_DP<0>
  DQS0_B_C  = M_I_CPU1_SB_DQS_DN<0>
  VSS46  = GND
  DQ4_B  = M_I_CPU1_SB_DQ<4>
  VSS47  = GND
  DQ5_B  = M_I_CPU1_SB_DQ<5>
  VSS48  = GND
  DQ8_B  = M_I_CPU1_SB_DQ<8>
  VSS49  = GND
  DQ9_B  = M_I_CPU1_SB_DQ<9>
  VSS50  = GND
  DQS1_B_T  = M_I_CPU1_SB_DQS_DP<1>
  DQS1_B_C  = M_I_CPU1_SB_DQS_DN<1>
  VSS51  = GND
  DQ12_B  = M_I_CPU1_SB_DQ<12>
  VSS52  = GND
  DQ13_B  = M_I_CPU1_SB_DQ<13>
  VSS53  = GND
  DQ16_B  = M_I_CPU1_SB_DQ<16>
  VSS54  = GND
  DQ17_B  = M_I_CPU1_SB_DQ<17>
  VSS55  = GND
  DQS2_B_T  = M_I_CPU1_SB_DQS_DP<2>
  DQS2_B_C  = M_I_CPU1_SB_DQS_DN<2>
  VSS56  = GND
  DQ20_B  = M_I_CPU1_SB_DQ<20>
  VSS57  = GND
  DQ21_B  = M_I_CPU1_SB_DQ<21>
  VSS58  = GND
  DQ24_B  = M_I_CPU1_SB_DQ<24>
  VSS59  = GND
  DQ25_B  = M_I_CPU1_SB_DQ<25>
  VSS60  = GND
  DQS3_B_T  = M_I_CPU1_SB_DQS_DP<3>
  DQS3_B_C  = M_I_CPU1_SB_DQS_DN<3>
  VSS61  = GND
  DQ28_B  = M_I_CPU1_SB_DQ<28>
  VSS62  = GND
  DQ29_B  = M_I_CPU1_SB_DQ<29>
  VSS63  = GND
  RFU1  = NC
  VIN_BULK1  = P12V_MEM_CPU1
  VIN_BULK2  = P12V_MEM_CPU1
  \pwr_good||fail_n\  = PWRGD_CHI_CPU1_DIMM
  HAS  = PD_CHI_CPU1_DIMM_SAA
  RFU2  = NC
  RFU3  = NC
  VSS64  = GND
  DQ2_A  = M_I_CPU1_SA_DQ<2>
  VSS65  = GND
  DQ3_A  = M_I_CPU1_SA_DQ<3>
  VSS66  = GND
  \dqs5_a_c||tdqs5_a_c||dqs5_a_t||tdqs5_a_t\  = M_I_CPU1_SA_DQS_DN<5>
  \dqs5_a_t||tdqs5_a_t\  = M_I_CPU1_SA_DQS_DP<5>
  VSS67  = GND
  DQ6_A  = M_I_CPU1_SA_DQ<6>
  VSS68  = GND
  DQ7_A  = M_I_CPU1_SA_DQ<7>
  VSS69  = GND
  DQ10_A  = M_I_CPU1_SA_DQ<10>
  VSS70  = GND
  DQ11_A  = M_I_CPU1_SA_DQ<11>
  VSS71  = GND
  \dqs6_a_c||tdqs6_a_c||dqs6_a_t||tdqs6_a_t\  = M_I_CPU1_SA_DQS_DN<6>
  \dqs6_a_t||tdqs6_a_t\  = M_I_CPU1_SA_DQS_DP<6>
  VSS72  = GND
  DQ14_A  = M_I_CPU1_SA_DQ<14>
  VSS73  = GND
  DQ15_A  = M_I_CPU1_SA_DQ<15>
  VSS74  = GND
  DQ18_A  = M_I_CPU1_SA_DQ<18>
  VSS75  = GND
  DQ19_A  = M_I_CPU1_SA_DQ<19>
  VSS76  = GND
  \dqs7_a_c||tdqs7_a_c\  = M_I_CPU1_SA_DQS_DN<7>
  \dqs7_a_t||tdqs7_a_t\  = M_I_CPU1_SA_DQS_DP<7>
  VSS77  = GND
  DQ22_A  = M_I_CPU1_SA_DQ<22>
  VSS78  = GND
  DQ23_A  = M_I_CPU1_SA_DQ<23>
  VSS79  = GND
  DQ26_A  = M_I_CPU1_SA_DQ<26>
  VSS80  = GND
  DQ27_A  = M_I_CPU1_SA_DQ<27>
  VSS81  = GND
  \dqs8_a_c||tdqs8_a_c\  = M_I_CPU1_SA_DQS_DN<8>
  \dqs8_a_t||tdqs8_a_t\  = M_I_CPU1_SA_DQS_DP<8>
  VSS82  = GND
  DQ30_A  = M_I_CPU1_SA_DQ<30>
  VSS83  = GND
  DQ31_A  = M_I_CPU1_SA_DQ<31>
  VSS84  = GND
  CB2_A  = M_I_CPU1_SA_CB<2>
  VSS85  = GND
  CB3_A  = M_I_CPU1_SA_CB<3>
  VSS86  = GND
  \dqs9_a_c||tdqs9_a_c\  = M_I_CPU1_SA_DQS_DN<9>
  \dqs9_a_t||tdqs9_a_t\  = M_I_CPU1_SA_DQS_DP<9>
  VSS87  = GND
  CB6_A  = M_I_CPU1_SA_CB<6>
  VSS88  = GND
  CB7_A  = M_I_CPU1_SA_CB<7>
  VSS89  = GND
  RESET_N  = M_I_CPU1_RESET_N
  VSS90  = GND
  CS1_A_N  = M_I_CPU1_SA_CS_N<1>
  VSS91  = GND
  CA1_A  = M_I_CPU1_SA_CA<1>
  VSS92  = GND
  CA3_A  = M_I_CPU1_SA_CA<3>
  VSS93  = GND
  CA5_A  = M_I_CPU1_SA_CA<5>
  VSS94  = GND
  CK_T  = M_I_CPU1_CLK_DP<0>
  CK_C  = M_I_CPU1_CLK_DN<0>
  VSS95  = GND
  RFU4  = NC
  CA1_B  = M_I_CPU1_SB_CA<1>
  VSS96  = GND
  CA3_B  = M_I_CPU1_SB_CA<3>
  VSS97  = GND
  CA5_B  = M_I_CPU1_SB_CA<5>
  VSS98  = GND
  PAR_B  = M_I_CPU1_SB_PAR
  VSS99  = GND
  CS1_B_N  = M_I_CPU1_SB_CS_N<1>
  VSS100  = GND
  RFU5  = NC
  RFU6  = NC
  VSS101  = GND
  CB6_B  = M_I_CPU1_SB_CB<6>
  VSS102  = GND
  CB7_B  = M_I_CPU1_SB_CB<7>
  VSS103  = GND
  DQS4_B_C  = M_I_CPU1_SB_DQS_DN<4>
  DQS4_B_T  = M_I_CPU1_SB_DQS_DP<4>
  VSS104  = GND
  CB2_B  = M_I_CPU1_SB_CB<2>
  VSS105  = GND
  CB3_B  = M_I_CPU1_SB_CB<3>
  VSS106  = GND
  DQ2_B  = M_I_CPU1_SB_DQ<2>
  VSS107  = GND
  DQ3_B  = M_I_CPU1_SB_DQ<3>
  VSS108  = GND
  \dqs5_b_c||tdqs5_b_c\  = M_I_CPU1_SB_DQS_DN<5>
  \dqs5_b_t||tdqs5_b_t\  = M_I_CPU1_SB_DQS_DP<5>
  VSS109  = GND
  DQ6_B  = M_I_CPU1_SB_DQ<6>
  VSS110  = GND
  DQ7_B  = M_I_CPU1_SB_DQ<7>
  VSS111  = GND
  DQ10_B  = M_I_CPU1_SB_DQ<10>
  VSS112  = GND
  DQ11_B  = M_I_CPU1_SB_DQ<11>
  VSS113  = GND
  \dqs6_b_c||tdqs6_b_c\  = M_I_CPU1_SB_DQS_DN<6>
  \dqs6_b_t||tdqs6_b_t\  = M_I_CPU1_SB_DQS_DP<6>
  VSS114  = GND
  DQ14_B  = M_I_CPU1_SB_DQ<14>
  VSS115  = GND
  DQ15_B  = M_I_CPU1_SB_DQ<15>
  VSS116  = GND
  DQ18_B  = M_I_CPU1_SB_DQ<18>
  VSS117  = GND
  DQ19_B  = M_I_CPU1_SB_DQ<19>
  VSS118  = GND
  \dqs7_b_c||tdqs7_b_c\  = M_I_CPU1_SB_DQS_DN<7>
  \dqs7_b_t||tdqs7_b_t\  = M_I_CPU1_SB_DQS_DP<7>
  VSS119  = GND
  DQ22_B  = M_I_CPU1_SB_DQ<22>
  VSS120  = GND
  DQ23_B  = M_I_CPU1_SB_DQ<23>
  VSS121  = GND
  DQ26_B  = M_I_CPU1_SB_DQ<26>
  VSS122  = GND
  DQ27_B  = M_I_CPU1_SB_DQ<27>
  VSS123  = GND
  \dqs8_b_c||tdqs8_b_c\  = M_I_CPU1_SB_DQS_DN<8>
  \dqs8_b_t||tdqs8_b_t\  = M_I_CPU1_SB_DQS_DP<8>
  VSS124  = GND
  DQ30_B  = M_I_CPU1_SB_DQ<30>
  VSS125  = GND
  DQ31_B  = M_I_CPU1_SB_DQ<31>
  VSS126  = GND
  G1  = GND
  G2  = GND
  G3  = GND

(kicad_pcb
	(version 20260206)
	(generator "pcbnew")
	(generator_version "10.0")
	(general
		(thickness 1.6)
		(legacy_teardrops no)
	)
	(paper "A4")
	(title_block
		(title "04192023_DAF0TMB3IC0_F0TG_MB_C_brd_V02_OCP.brd")
		(comment 1 "Grand Teton / footprint 230 of 8354 (J100), pads 185-230 of 291")
	)
	(layers
		(0 "F.Cu" signal "TOP")
		(4 "In1.Cu" signal "GND")
		(6 "In2.Cu" signal "IN1")
		(8 "In3.Cu" signal "GND1")
		(10 "In4.Cu" signal "IN2")
		(12 "In5.Cu" signal "GND2")
		(14 "In6.Cu" signal "IN3")
		(16 "In7.Cu" signal "GND3")
		(18 "In8.Cu" signal "VCC")
		(20 "In9.Cu" signal "VCC1")
		(22 "In10.Cu" signal "GND4")
		(24 "In11.Cu" signal "IN4")
		(26 "In12.Cu" signal "GND5")
		(28 "In13.Cu" signal "IN5")
		(30 "In14.Cu" signal "GND6")
		(32 "In15.Cu" signal "IN6")
		(34 "In16.Cu" signal "GND7")
		(2 "B.Cu" signal "BOTTOM")
		(9 "F.Adhes" user "F.Adhesive")
		(11 "B.Adhes" user "B.Adhesive")
		(13 "F.Paste" user "Package Geometry/Pastemask Top")
		(15 "B.Paste" user "Package Geometry/Pastemask Bottom")
		(5 "F.SilkS" user "Ref Des/Silkscreen Top")
		(7 "B.SilkS" user "Ref Des/Silkscreen Bottom")
		(1 "F.Mask" user "Board Geometry/Soldermask Top")
		(3 "B.Mask" user "Board Geometry/Soldermask Bottom")
		(17 "Dwgs.User" user "User.Drawings")
		(19 "Cmts.User" user "User.Comments")
		(21 "Eco1.User" user "User.Eco1")
		(23 "Eco2.User" user "User.Eco2")
		(25 "Edge.Cuts" user "Board Geometry/Outline")
		(27 "Margin" user)
		(31 "F.CrtYd" user "Package Geometry/Place Bound Top")
		(29 "B.CrtYd" user "Package Geometry/Place Bound Bottom")
		(35 "F.Fab" user "Ref Des/Assembly Top")
		(33 "B.Fab" user "Ref Des/Assembly Bottom")
	)
	(footprint ""
		(layer "F.Cu")
		(at 181.566058 -255.560322 180)
		(property "Reference" "J100"
			(at -2.7178 -81.857088 0)
			(unlocked yes)
			(layer "F.SilkS")
			(effects
				(font
					(size 0.7874 0.5842)
					(thickness 0.1524)
				)
			)
		)
		(property "Value" ""
			(at 0 0 180)
			(layer "F.Fab")
			(effects
				(font
					(size 1.27 1.27)
				)
			)
		)
		(duplicate_pad_numbers_are_jumpers no)
		(pad "185" smd rect
			(at 2.050034 -29.325062 90)
			(size 0.519938 1.4986)
			(layers "F.Cu" "F.Mask" "F.Paste")
			(net "M_I_CPU1_SA_DQ<26>")
		)
		(pad "186" smd rect
			(at 2.050034 -28.474924 90)
			(size 0.519938 1.4986)
			(layers "F.Cu" "F.Mask" "F.Paste")
			(net "GND")
		)
		(pad "187" smd rect
			(at 2.050034 -27.62504 90)
			(size 0.519938 1.4986)
			(layers "F.Cu" "F.Mask" "F.Paste")
			(net "M_I_CPU1_SA_DQ<27>")
		)
		(pad "188" smd rect
			(at 2.050034 -26.774902 90)
			(size 0.519938 1.4986)
			(layers "F.Cu" "F.Mask" "F.Paste")
			(net "GND")
		)
		(pad "189" smd rect
			(at 2.050034 -25.925018 90)
			(size 0.519938 1.4986)
			(layers "F.Cu" "F.Mask" "F.Paste")
			(net "M_I_CPU1_SA_DQS_DN<8>")
		)
		(pad "190" smd rect
			(at 2.050034 -25.07488 90)
			(size 0.519938 1.4986)
			(layers "F.Cu" "F.Mask" "F.Paste")
			(net "M_I_CPU1_SA_DQS_DP<8>")
		)
		(pad "191" smd rect
			(at 2.050034 -24.224996 90)
			(size 0.519938 1.4986)
			(layers "F.Cu" "F.Mask" "F.Paste")
			(net "GND")
		)
		(pad "192" smd rect
			(at 2.050034 -23.375112 90)
			(size 0.519938 1.4986)
			(layers "F.Cu" "F.Mask" "F.Paste")
			(net "M_I_CPU1_SA_DQ<30>")
		)
		(pad "193" smd rect
			(at 2.050034 -22.524974 90)
			(size 0.519938 1.4986)
			(layers "F.Cu" "F.Mask" "F.Paste")
			(net "GND")
		)
		(pad "194" smd rect
			(at 2.050034 -21.67509 90)
			(size 0.519938 1.4986)
			(layers "F.Cu" "F.Mask" "F.Paste")
			(net "M_I_CPU1_SA_DQ<31>")
		)
		(pad "195" smd rect
			(at 2.050034 -20.824952 90)
			(size 0.519938 1.4986)
			(layers "F.Cu" "F.Mask" "F.Paste")
			(net "GND")
		)
		(pad "196" smd rect
			(at 2.050034 -19.975068 90)
			(size 0.519938 1.4986)
			(layers "F.Cu" "F.Mask" "F.Paste")
			(net "M_I_CPU1_SA_CB<2>")
		)
		(pad "197" smd rect
			(at 2.050034 -19.12493 90)
			(size 0.519938 1.4986)
			(layers "F.Cu" "F.Mask" "F.Paste")
			(net "GND")
		)
		(pad "198" smd rect
			(at 2.050034 -18.275046 90)
			(size 0.519938 1.4986)
			(layers "F.Cu" "F.Mask" "F.Paste")
			(net "M_I_CPU1_SA_CB<3>")
		)
		(pad "199" smd rect
			(at 2.050034 -17.424908 90)
			(size 0.519938 1.4986)
			(layers "F.Cu" "F.Mask" "F.Paste")
			(net "GND")
		)
		(pad "200" smd rect
			(at 2.050034 -16.575024 90)
			(size 0.519938 1.4986)
			(layers "F.Cu" "F.Mask" "F.Paste")
			(net "M_I_CPU1_SA_DQS_DN<9>")
		)
		(pad "201" smd rect
			(at 2.050034 -15.724886 90)
			(size 0.519938 1.4986)
			(layers "F.Cu" "F.Mask" "F.Paste")
			(net "M_I_CPU1_SA_DQS_DP<9>")
		)
		(pad "202" smd rect
			(at 2.050034 -14.875002 90)
			(size 0.519938 1.4986)
			(layers "F.Cu" "F.Mask" "F.Paste")
			(net "GND")
		)
		(pad "203" smd rect
			(at 2.050034 -14.025118 90)
			(size 0.519938 1.4986)
			(layers "F.Cu" "F.Mask" "F.Paste")
			(net "M_I_CPU1_SA_CB<6>")
		)
		(pad "204" smd rect
			(at 2.050034 -13.17498 90)
			(size 0.519938 1.4986)
			(layers "F.Cu" "F.Mask" "F.Paste")
			(net "GND")
		)
		(pad "205" smd rect
			(at 2.050034 -12.325096 90)
			(size 0.519938 1.4986)
			(layers "F.Cu" "F.Mask" "F.Paste")
			(net "M_I_CPU1_SA_CB<7>")
		)
		(pad "206" smd rect
			(at 2.050034 -11.474958 90)
			(size 0.519938 1.4986)
			(layers "F.Cu" "F.Mask" "F.Paste")
			(net "GND")
		)
		(pad "207" smd rect
			(at 2.050034 -10.625074 90)
			(size 0.519938 1.4986)
			(layers "F.Cu" "F.Mask" "F.Paste")
			(net "M_I_CPU1_RESET_N")
		)
		(pad "208" smd rect
			(at 2.050034 -9.774936 90)
			(size 0.519938 1.4986)
			(layers "F.Cu" "F.Mask" "F.Paste")
			(net "GND")
		)
		(pad "209" smd rect
			(at 2.050034 -8.925052 90)
			(size 0.519938 1.4986)
			(layers "F.Cu" "F.Mask" "F.Paste")
			(net "M_I_CPU1_SA_CS_N<1>")
		)
		(pad "210" smd rect
			(at 2.050034 -8.074914 90)
			(size 0.519938 1.4986)
			(layers "F.Cu" "F.Mask" "F.Paste")
			(net "GND")
		)
		(pad "211" smd rect
			(at 2.050034 -7.22503 90)
			(size 0.519938 1.4986)
			(layers "F.Cu" "F.Mask" "F.Paste")
			(net "M_I_CPU1_SA_CA<1>")
		)
		(pad "212" smd rect
			(at 2.050034 -6.374892 90)
			(size 0.519938 1.4986)
			(layers "F.Cu" "F.Mask" "F.Paste")
			(net "GND")
		)
		(pad "213" smd rect
			(at 2.050034 -5.525008 90)
			(size 0.519938 1.4986)
			(layers "F.Cu" "F.Mask" "F.Paste")
			(net "M_I_CPU1_SA_CA<3>")
		)
		(pad "214" smd rect
			(at 2.050034 -4.675124 90)
			(size 0.519938 1.4986)
			(layers "F.Cu" "F.Mask" "F.Paste")
			(net "GND")
		)
		(pad "215" smd rect
			(at 2.050034 -3.824986 90)
			(size 0.519938 1.4986)
			(layers "F.Cu" "F.Mask" "F.Paste")
			(net "M_I_CPU1_SA_CA<5>")
		)
		(pad "216" smd rect
			(at 2.050034 -2.975102 90)
			(size 0.519938 1.4986)
			(layers "F.Cu" "F.Mask" "F.Paste")
			(net "GND")
		)
		(pad "217" smd rect
			(at 2.050034 -2.124964 90)
			(size 0.519938 1.4986)
			(layers "F.Cu" "F.Mask" "F.Paste")
			(net "M_I_CPU1_CLK_DP<0>")
		)
		(pad "218" smd rect
			(at 2.050034 -1.27508 90)
			(size 0.519938 1.4986)
			(layers "F.Cu" "F.Mask" "F.Paste")
			(net "M_I_CPU1_CLK_DN<0>")
		)
		(pad "219" smd rect
			(at 2.050034 -0.424942 90)
			(size 0.519938 1.4986)
			(layers "F.Cu" "F.Mask" "F.Paste")
			(net "GND")
		)
		(pad "220" smd rect
			(at 2.050034 5.525008 90)
			(size 0.519938 1.4986)
			(layers "F.Cu" "F.Mask" "F.Paste")
			(net "Net_2372")
		)
		(pad "221" smd rect
			(at 2.050034 6.374892 90)
			(size 0.519938 1.4986)
			(layers "F.Cu" "F.Mask" "F.Paste")
			(net "M_I_CPU1_SB_CA<1>")
		)
		(pad "222" smd rect
			(at 2.050034 7.22503 90)
			(size 0.519938 1.4986)
			(layers "F.Cu" "F.Mask" "F.Paste")
			(net "GND")
		)
		(pad "223" smd rect
			(at 2.050034 8.074914 90)
			(size 0.519938 1.4986)
			(layers "F.Cu" "F.Mask" "F.Paste")
			(net "M_I_CPU1_SB_CA<3>")
		)
		(pad "224" smd rect
			(at 2.050034 8.925052 90)
			(size 0.519938 1.4986)
			(layers "F.Cu" "F.Mask" "F.Paste")
			(net "GND")
		)
		(pad "225" smd rect
			(at 2.050034 9.774936 90)
			(size 0.519938 1.4986)
			(layers "F.Cu" "F.Mask" "F.Paste")
			(net "M_I_CPU1_SB_CA<5>")
		)
		(pad "226" smd rect
			(at 2.050034 10.625074 90)
			(size 0.519938 1.4986)
			(layers "F.Cu" "F.Mask" "F.Paste")
			(net "GND")
		)
		(pad "227" smd rect
			(at 2.050034 11.474958 90)
			(size 0.519938 1.4986)
			(layers "F.Cu" "F.Mask" "F.Paste")
			(net "M_I_CPU1_SB_PAR")
		)
		(pad "228" smd rect
			(at 2.050034 12.325096 90)
			(size 0.519938 1.4986)
			(layers "F.Cu" "F.Mask" "F.Paste")
			(net "GND")
		)
		(pad "229" smd rect
			(at 2.050034 13.17498 90)
			(size 0.519938 1.4986)
			(layers "F.Cu" "F.Mask" "F.Paste")
			(net "M_I_CPU1_SB_CS_N<1>")
		)
		(pad "230" smd rect
			(at 2.050034 14.025118 90)
			(size 0.519938 1.4986)
			(layers "F.Cu" "F.Mask" "F.Paste")
			(net "GND")
		)
	)
)
